# S9S_MB_2U (Grand Teton) — schematic netlist excerpt (pin names and nets, part order shuffled) for the footprints in the layout excerpt that follows; sources: Cadence DE-HDL packaged netlist, KiCad conversion of 03242023_DA0F0TMBIJ0_F0T_Motherboard_J_brd_V01_OCP.brd

R3717  Q_RES  0 5% CHIP  pkg 0402LF  page 233 : A = SMB_LM75_1_3V3AUX_SCL_R ; B = SMB_LM75_1_3V3AUX_SCL
R4073  Q_RES  4.7K 5% CHIP  pkg 0402LF  page 192 : A = P12V_E1S_EN_0_R ; B = GND

(kicad_pcb
	(version 20260206)
	(generator "pcbnew")
	(generator_version "10.0")
	(general
		(thickness 1.6)
		(legacy_teardrops no)
	)
	(paper "A4")
	(title_block
		(title "03242023_DA0F0TMBIJ0_F0T_Motherboard_J_brd_V01_OCP.brd")
		(comment 1 "Grand Teton / footprints 1033-1034 of 6105")
	)
	(layers
		(0 "F.Cu" signal "TOP")
		(4 "In1.Cu" signal "GND")
		(6 "In2.Cu" signal "IN1")
		(8 "In3.Cu" signal "GND1")
		(10 "In4.Cu" signal "IN2")
		(12 "In5.Cu" signal "GND2")
		(14 "In6.Cu" signal "IN3")
		(16 "In7.Cu" signal "GND3")
		(18 "In8.Cu" signal "VCC")
		(20 "In9.Cu" signal "VCC1")
		(22 "In10.Cu" signal "GND4")
		(24 "In11.Cu" signal "IN4")
		(26 "In12.Cu" signal "GND5")
		(28 "In13.Cu" signal "IN5")
		(30 "In14.Cu" signal "GND6")
		(32 "In15.Cu" signal "IN6")
		(34 "In16.Cu" signal "GND7")
		(2 "B.Cu" signal "BOTTOM")
		(9 "F.Adhes" user "F.Adhesive")
		(11 "B.Adhes" user "B.Adhesive")
		(13 "F.Paste" user "Package Geometry/Pastemask Top")
		(15 "B.Paste" user "Package Geometry/Pastemask Bottom")
		(5 "F.SilkS" user "Ref Des/Silkscreen Top")
		(7 "B.SilkS" user "Ref Des/Silkscreen Bottom")
		(1 "F.Mask" user "Board Geometry/Soldermask Top")
		(3 "B.Mask" user "Board Geometry/Soldermask Bottom")
		(17 "Dwgs.User" user "User.Drawings")
		(19 "Cmts.User" user "User.Comments")
		(21 "Eco1.User" user "User.Eco1")
		(23 "Eco2.User" user "User.Eco2")
		(25 "Edge.Cuts" user "Board Geometry/Outline")
		(27 "Margin" user)
		(31 "F.CrtYd" user "Package Geometry/Place Bound Top")
		(29 "B.CrtYd" user "Package Geometry/Place Bound Bottom")
		(35 "F.Fab" user "Ref Des/Assembly Top")
		(33 "B.Fab" user "Ref Des/Assembly Bottom")
	)
	(footprint ""
		(layer "F.Cu")
		(at 54.242716 -108.89869 180)
		(property "Reference" "R3717"
			(at 0 0 180)
			(layer "F.SilkS")
			(hide yes)
			(effects
				(font
					(size 1.27 1.27)
				)
			)
		)
		(property "Value" ""
			(at 0 0 180)
			(layer "F.Fab")
			(effects
				(font
					(size 1.27 1.27)
				)
			)
		)
		(duplicate_pad_numbers_are_jumpers no)
		(fp_line
			(start 0.7874 0.4064)
			(end -0.7874 0.4064)
			(stroke
				(width 0.1524)
				(type default)
			)
			(layer "F.SilkS")
		)
		(fp_line
			(start 0.7874 -0.4064)
			(end 0.7874 0.4064)
			(stroke
				(width 0.1524)
				(type default)
			)
			(layer "F.SilkS")
		)
		(fp_line
			(start -0.7874 0.4064)
			(end -0.7874 -0.4064)
			(stroke
				(width 0.1524)
				(type default)
			)
			(layer "F.SilkS")
		)
		(fp_line
			(start -0.7874 -0.4064)
			(end 0.7874 -0.4064)
			(stroke
				(width 0.1524)
				(type default)
			)
			(layer "F.SilkS")
		)
		(fp_line
			(start 0.67945 0.3048)
			(end 0.120396 0.3048)
			(stroke
				(width 0.1)
				(type default)
			)
			(layer "F.Fab")
		)
		(fp_line
			(start 0.67945 -0.3048)
			(end 0.67945 0.3048)
			(stroke
				(width 0.1)
				(type default)
			)
			(layer "F.Fab")
		)
		(fp_line
			(start 0.12065 -0.2794)
			(end 0.12065 -0.3048)
			(stroke
				(width 0.1)
				(type default)
			)
			(layer "F.Fab")
		)
		(fp_line
			(start 0.12065 -0.3048)
			(end 0.67945 -0.3048)
			(stroke
				(width 0.1)
				(type default)
			)
			(layer "F.Fab")
		)
		(fp_line
			(start 0.120396 0.3048)
			(end 0.120396 0.2794)
			(stroke
				(width 0.1)
				(type default)
			)
			(layer "F.Fab")
		)
		(fp_line
			(start 0.120396 0.2794)
			(end -0.12065 0.2794)
			(stroke
				(width 0.1)
				(type default)
			)
			(layer "F.Fab")
		)
		(fp_line
			(start -0.12065 0.3048)
			(end -0.67945 0.3048)
			(stroke
				(width 0.1)
				(type default)
			)
			(layer "F.Fab")
		)
		(fp_line
			(start -0.12065 0.2794)
			(end -0.12065 0.3048)
			(stroke
				(width 0.1)
				(type default)
			)
			(layer "F.Fab")
		)
		(fp_line
			(start -0.12065 -0.2794)
			(end 0.12065 -0.2794)
			(stroke
				(width 0.1)
				(type default)
			)
			(layer "F.Fab")
		)
		(fp_line
			(start -0.12065 -0.305054)
			(end -0.12065 -0.2794)
			(stroke
				(width 0.1)
				(type default)
			)
			(layer "F.Fab")
		)
		(fp_line
			(start -0.67945 0.3048)
			(end -0.67945 -0.305054)
			(stroke
				(width 0.1)
				(type default)
			)
			(layer "F.Fab")
		)
		(fp_line
			(start -0.67945 -0.305054)
			(end -0.12065 -0.305054)
			(stroke
				(width 0.1)
				(type default)
			)
			(layer "F.Fab")
		)
		(pad "1" smd circle
			(at -0.40005 0 180)
			(size 0 0)
			(layers "F.Cu" "F.Mask" "F.Paste")
			(net "SMB_LM75_1_3V3AUX_SCL_R")
		)
		(pad "2" smd circle
			(at 0.40005 0 180)
			(size 0 0)
			(layers "F.Cu" "F.Mask" "F.Paste")
			(net "SMB_LM75_1_3V3AUX_SCL")
		)
	)
	(footprint ""
		(layer "F.Cu")
		(at 294.82288 -46.954948 -90)
		(property "Reference" "R4073"
			(at 0 0 270)
			(layer "F.SilkS")
			(hide yes)
			(effects
				(font
					(size 1.27 1.27)
				)
			)
		)
		(property "Value" ""
			(at 0 0 270)
			(layer "F.Fab")
			(effects
				(font
					(size 1.27 1.27)
				)
			)
		)
		(duplicate_pad_numbers_are_jumpers no)
		(fp_line
			(start -0.7874 0.4064)
			(end -0.7874 -0.4064)
			(stroke
				(width 0.1524)
				(type default)
			)
			(layer "F.SilkS")
		)
		(fp_line
			(start 0.7874 0.4064)
			(end -0.7874 0.4064)
			(stroke
				(width 0.1524)
				(type default)
			)
			(layer "F.SilkS")
		)
		(fp_line
			(start -0.7874 -0.4064)
			(end 0.7874 -0.4064)
			(stroke
				(width 0.1524)
				(type default)
			)
			(layer "F.SilkS")
		)
		(fp_line
			(start 0.7874 -0.4064)
			(end 0.7874 0.4064)
			(stroke
				(width 0.1524)
				(type default)
			)
			(layer "F.SilkS")
		)
		(fp_line
			(start -0.67945 0.3048)
			(end -0.67945 -0.305054)
			(stroke
				(width 0.1)
				(type default)
			)
			(layer "F.Fab")
		)
		(fp_line
			(start -0.12065 0.3048)
			(end -0.67945 0.3048)
			(stroke
				(width 0.1)
				(type default)
			)
			(layer "F.Fab")
		)
		(fp_line
			(start 0.120396 0.3048)
			(end 0.120396 0.2794)
			(stroke
				(width 0.1)
				(type default)
			)
			(layer "F.Fab")
		)
		(fp_line
			(start 0.67945 0.3048)
			(end 0.120396 0.3048)
			(stroke
				(width 0.1)
				(type default)
			)
			(layer "F.Fab")
		)
		(fp_line
			(start -0.12065 0.2794)
			(end -0.12065 0.3048)
			(stroke
				(width 0.1)
				(type default)
			)
			(layer "F.Fab")
		)
		(fp_line
			(start 0.120396 0.2794)
			(end -0.12065 0.2794)
			(stroke
				(width 0.1)
				(type default)
			)
			(layer "F.Fab")
		)
		(fp_line
			(start -0.12065 -0.2794)
			(end 0.12065 -0.2794)
			(stroke
				(width 0.1)
				(type default)
			)
			(layer "F.Fab")
		)
		(fp_line
			(start 0.12065 -0.2794)
			(end 0.12065 -0.3048)
			(stroke
				(width 0.1)
				(type default)
			)
			(layer "F.Fab")
		)
		(fp_line
			(start 0.12065 -0.3048)
			(end 0.67945 -0.3048)
			(stroke
				(width 0.1)
				(type default)
			)
			(layer "F.Fab")
		)
		(fp_line
			(start 0.67945 -0.3048)
			(end 0.67945 0.3048)
			(stroke
				(width 0.1)
				(type default)
			)
			(layer "F.Fab")
		)
		(fp_line
			(start -0.67945 -0.305054)
			(end -0.12065 -0.305054)
			(stroke
				(width 0.1)
				(type default)
			)
			(layer "F.Fab")
		)
		(fp_line
			(start -0.12065 -0.305054)
			(end -0.12065 -0.2794)
			(stroke
				(width 0.1)
				(type default)
			)
			(layer "F.Fab")
		)
		(pad "1" smd circle
			(at -0.40005 0 270)
			(size 0 0)
			(layers "F.Cu" "F.Mask" "F.Paste")
			(net "P12V_E1S_EN_0_R")
		)
		(pad "2" smd circle
			(at 0.40005 0 270)
			(size 0 0)
			(layers "F.Cu" "F.Mask" "F.Paste")
			(net "GND")
		)
	)
)
